# TIMECARD (Time Appliance Project (Time Card)) — schematic netlist excerpt (pin names and nets, part order shuffled) for the footprints in the layout excerpt that follows; sources: Cadence DE-HDL packaged netlist, KiCad conversion of R4006-B0001-02_R01.brd

R341  RESISTOR  4.7KOHM 1%  pkg SMC_0402R_H016  page 20 : \1\ = XP3R3V_FPGA ; \2\ = BNO080_EVN_SDA
R51  RESISTOR  10KOHM 1%  pkg SMC_0402R_H016  page 28 : \1\ = XP3R3V ; \2\ = R_XP3R3V_PG

(kicad_pcb
	(version 20260206)
	(generator "pcbnew")
	(generator_version "10.0")
	(general
		(thickness 1.6)
		(legacy_teardrops no)
	)
	(paper "A4")
	(title_block
		(title "timecard-production-celestica-r4006 — R4006-B0001-02_R01.brd")
		(comment 1 "Time Appliance Project (Time Card) / footprints 1043-1044 of 1113")
	)
	(layers
		(0 "F.Cu" signal "TOP")
		(4 "In1.Cu" signal "L02_GND1")
		(6 "In2.Cu" signal "L03_SIG1")
		(8 "In3.Cu" signal "L04_GND2")
		(10 "In4.Cu" signal "L05_VCC1")
		(12 "In5.Cu" signal "L06_VCC2")
		(14 "In6.Cu" signal "L07_GND3")
		(16 "In7.Cu" signal "L08_SIG2")
		(18 "In8.Cu" signal "L09_GND4")
		(2 "B.Cu" signal "BOTTOM")
		(9 "F.Adhes" user "F.Adhesive")
		(11 "B.Adhes" user "B.Adhesive")
		(13 "F.Paste" user "Package Geometry/Pastemask Top")
		(15 "B.Paste" user "Package Geometry/Pastemask Bottom")
		(5 "F.SilkS" user "Ref Des/Silkscreen Top")
		(7 "B.SilkS" user "Ref Des/Silkscreen Bottom")
		(1 "F.Mask" user "Board Geometry/Soldermask Top")
		(3 "B.Mask" user "Board Geometry/Soldermask Bottom")
		(17 "Dwgs.User" user "User.Drawings")
		(19 "Cmts.User" user "User.Comments")
		(21 "Eco1.User" user "User.Eco1")
		(23 "Eco2.User" user "User.Eco2")
		(25 "Edge.Cuts" user "Board Geometry/Outline")
		(27 "Margin" user)
		(31 "F.CrtYd" user "Package Geometry/Place Bound Top")
		(29 "B.CrtYd" user "Package Geometry/Place Bound Bottom")
		(35 "F.Fab" user "Ref Des/Assembly Top")
		(33 "B.Fab" user "Ref Des/Assembly Bottom")
	)
	(footprint ""
		(layer "B.Cu")
		(at 88.519 -73.279 90)
		(property "Reference" "R341"
			(at -3.556 -0.16637 270)
			(unlocked yes)
			(layer "B.SilkS")
			(effects
				(font
					(size 0.7874 0.5842)
					(thickness 0.1524)
				)
				(justify mirror)
			)
		)
		(property "Value" "VAL*"
			(at -0.02032 2.13233 90)
			(unlocked yes)
			(layer "B.Fab")
			(hide yes)
			(effects
				(font
					(size 0.7874 0.5842)
					(thickness 0.1524)
				)
				(justify mirror)
			)
		)
		(property "Device Type" "RESISTOR-G155-14701-01,4.7KOHMA"
			(at -0.008382 1.210564 90)
			(unlocked yes)
			(layer "B.Fab")
			(hide yes)
			(effects
				(font
					(size 0.7874 0.5842)
					(thickness 0.1524)
				)
				(justify mirror)
			)
		)
		(property "User Part Number" "PARTNUM*"
			(at -0.02032 4.024884 90)
			(unlocked yes)
			(layer "Cmts.User")
			(hide yes)
			(effects
				(font
					(size 0.7874 0.5842)
					(thickness 0.1524)
				)
				(justify mirror)
			)
		)
		(property "Tolerance" "TOL*"
			(at -0.044704 3.05435 90)
			(unlocked yes)
			(layer "Cmts.User")
			(hide yes)
			(effects
				(font
					(size 0.7874 0.5842)
					(thickness 0.1524)
				)
				(justify mirror)
			)
		)
		(duplicate_pad_numbers_are_jumpers no)
		(fp_line
			(start 1.143 -0.5588)
			(end 1.143 0.5588)
			(stroke
				(width 0.1)
				(type default)
			)
			(layer "B.SilkS")
		)
		(fp_line
			(start -1.143 -0.5588)
			(end 1.143 -0.5588)
			(stroke
				(width 0.1)
				(type default)
			)
			(layer "B.SilkS")
		)
		(fp_line
			(start 1.143 0.5588)
			(end -1.143 0.5588)
			(stroke
				(width 0.1)
				(type default)
			)
			(layer "B.SilkS")
		)
		(fp_line
			(start -1.143 0.5588)
			(end -1.143 -0.5588)
			(stroke
				(width 0.1)
				(type default)
			)
			(layer "B.SilkS")
		)
		(fp_rect
			(start 1.143 -0.5588)
			(end -1.143 0.5588)
			(stroke
				(width 0)
				(type default)
			)
			(fill no)
			(layer "B.CrtYd")
		)
		(fp_line
			(start 0.508 -0.3048)
			(end 0.508 0.3048)
			(stroke
				(width 0.1)
				(type default)
			)
			(layer "B.Fab")
		)
		(fp_line
			(start -0.508 -0.3048)
			(end 0.508 -0.3048)
			(stroke
				(width 0.1)
				(type default)
			)
			(layer "B.Fab")
		)
		(fp_line
			(start 0.508 0.3048)
			(end -0.508 0.3048)
			(stroke
				(width 0.1)
				(type default)
			)
			(layer "B.Fab")
		)
		(fp_line
			(start -0.508 0.3048)
			(end -0.508 -0.3048)
			(stroke
				(width 0.1)
				(type default)
			)
			(layer "B.Fab")
		)
		(pad "1" smd rect
			(at 0.5334 0 270)
			(size 0.7112 0.6096)
			(layers "B.Cu" "B.Mask" "B.Paste")
			(net "XP3R3V_FPGA")
		)
		(pad "2" smd rect
			(at -0.5334 0 270)
			(size 0.7112 0.6096)
			(layers "B.Cu" "B.Mask" "B.Paste")
			(net "BNO080_EVN_SDA")
		)
		(zone
			(layer "B.Cu")
			(hatch none 0.5)
			(connect_pads
				(clearance 0)
			)
			(min_thickness 0.25)
			(keepout
				(tracks allowed)
				(vias not_allowed)
				(pads allowed)
				(copperpour not_allowed)
				(footprints allowed)
			)
			(placement
				(enabled no)
				(sheetname "")
			)
			(fill
				(thermal_gap 0.5)
				(thermal_bridge_width 0.5)
				(island_removal_mode 0)
			)
			(polygon
				(pts
					(xy 88.2142 -73.3552) (xy 88.2142 -73.2028) (xy 88.8238 -73.2028) (xy 88.8238 -73.3552)
				)
			)
		)
	)
	(footprint ""
		(layer "B.Cu")
		(at 90.424 -104.902)
		(property "Reference" "R51"
			(at 0.127 -2.88163 0)
			(unlocked yes)
			(layer "B.SilkS")
			(effects
				(font
					(size 0.7874 0.5842)
					(thickness 0.1524)
				)
				(justify mirror)
			)
		)
		(property "Value" "VAL*"
			(at -0.02032 2.13233 0)
			(unlocked yes)
			(layer "B.Fab")
			(hide yes)
			(effects
				(font
					(size 0.7874 0.5842)
					(thickness 0.1524)
				)
				(justify mirror)
			)
		)
		(property "Tolerance" "TOL*"
			(at -0.044704 3.05435 0)
			(unlocked yes)
			(layer "Cmts.User")
			(hide yes)
			(effects
				(font
					(size 0.7874 0.5842)
					(thickness 0.1524)
				)
				(justify mirror)
			)
		)
		(property "User Part Number" "PARTNUM*"
			(at -0.02032 4.024884 0)
			(unlocked yes)
			(layer "Cmts.User")
			(hide yes)
			(effects
				(font
					(size 0.7874 0.5842)
					(thickness 0.1524)
				)
				(justify mirror)
			)
		)
		(property "Device Type" "RESISTOR-G155-11002-01,10KOHM,A"
			(at -0.008382 1.210564 0)
			(unlocked yes)
			(layer "B.Fab")
			(hide yes)
			(effects
				(font
					(size 0.7874 0.5842)
					(thickness 0.1524)
				)
				(justify mirror)
			)
		)
		(duplicate_pad_numbers_are_jumpers no)
		(fp_line
			(start -1.143 -0.5588)
			(end 1.143 -0.5588)
			(stroke
				(width 0.1)
				(type default)
			)
			(layer "B.SilkS")
		)
		(fp_line
			(start -1.143 0.5588)
			(end -1.143 -0.5588)
			(stroke
				(width 0.1)
				(type default)
			)
			(layer "B.SilkS")
		)
		(fp_line
			(start 1.143 -0.5588)
			(end 1.143 0.5588)
			(stroke
				(width 0.1)
				(type default)
			)
			(layer "B.SilkS")
		)
		(fp_line
			(start 1.143 0.5588)
			(end -1.143 0.5588)
			(stroke
				(width 0.1)
				(type default)
			)
			(layer "B.SilkS")
		)
		(fp_poly
			(pts
				(xy 1.143 0.5588) (xy -1.143 0.5588) (xy -1.143 -0.5588) (xy 1.143 -0.5588)
			)
			(stroke
				(width 0)
				(type default)
			)
			(fill no)
			(layer "B.CrtYd")
		)
		(fp_line
			(start -0.508 -0.3048)
			(end 0.508 -0.3048)
			(stroke
				(width 0.1)
				(type default)
			)
			(layer "B.Fab")
		)
		(fp_line
			(start -0.508 0.3048)
			(end -0.508 -0.3048)
			(stroke
				(width 0.1)
				(type default)
			)
			(layer "B.Fab")
		)
		(fp_line
			(start 0.508 -0.3048)
			(end 0.508 0.3048)
			(stroke
				(width 0.1)
				(type default)
			)
			(layer "B.Fab")
		)
		(fp_line
			(start 0.508 0.3048)
			(end -0.508 0.3048)
			(stroke
				(width 0.1)
				(type default)
			)
			(layer "B.Fab")
		)
		(pad "1" smd rect
			(at 0.5334 0 180)
			(size 0.7112 0.6096)
			(layers "B.Cu" "B.Mask" "B.Paste")
			(net "XP3R3V")
		)
		(pad "2" smd rect
			(at -0.5334 0 180)
			(size 0.7112 0.6096)
			(layers "B.Cu" "B.Mask" "B.Paste")
			(net "R_XP3R3V_PG")
		)
		(zone
			(layer "B.Cu")
			(hatch none 0.5)
			(connect_pads
				(clearance 0)
			)
			(min_thickness 0.25)
			(keepout
				(tracks allowed)
				(vias not_allowed)
				(pads allowed)
				(copperpour not_allowed)
				(footprints allowed)
			)
			(placement
				(enabled no)
				(sheetname "")
			)
			(fill
				(thermal_gap 0.5)
				(thermal_bridge_width 0.5)
				(island_removal_mode 0)
			)
			(polygon
				(pts
					(xy 90.5002 -104.5972) (xy 90.5002 -105.2068) (xy 90.3478 -105.2068) (xy 90.3478 -104.5972)
				)
			)
		)
		(zone
			(layer "B.Cu")
			(hatch none 0.5)
			(connect_pads
				(clearance 0)
			)
			(min_thickness 0.25)
			(keepout
				(tracks not_allowed)
				(vias allowed)
				(pads allowed)
				(copperpour not_allowed)
				(footprints allowed)
			)
			(placement
				(enabled no)
				(sheetname "")
			)
			(fill
				(thermal_gap 0.5)
				(thermal_bridge_width 0.5)
				(island_removal_mode 0)
			)
			(polygon
				(pts
					(xy 90.5002 -104.5972) (xy 90.5002 -105.2068) (xy 90.3478 -105.2068) (xy 90.3478 -104.5972)
				)
			)
		)
	)
)
